(kicad_pcb
	(version 20260206)
	(generator "pcbnew")
	(generator_version "10.0")
	(general
		(thickness 1.6)
		(legacy_teardrops no)
	)
	(paper "A4")
	(title_block
		(title "01162023_DA0F0TEBIF0_F0T_Expander_BD_F_brd_V02_OCP.brd")
		(comment 1 "Grand Teton / footprints 724-730 of 9728")
	)
	(layers
		(0 "F.Cu" signal "TOP")
		(4 "In1.Cu" signal "GND")
		(6 "In2.Cu" signal "VCC")
		(8 "In3.Cu" signal "VCC1")
		(10 "In4.Cu" signal "GND1")
		(12 "In5.Cu" signal "IN1")
		(14 "In6.Cu" signal "GND2")
		(16 "In7.Cu" signal "IN2")
		(18 "In8.Cu" signal "GND3")
		(20 "In9.Cu" signal "IN3")
		(22 "In10.Cu" signal "GND4")
		(24 "In11.Cu" signal "IN4")
		(26 "In12.Cu" signal "GND5")
		(28 "In13.Cu" signal "IN5")
		(30 "In14.Cu" signal "GND6")
		(32 "In15.Cu" signal "IN6")
		(34 "In16.Cu" signal "GND7")
		(2 "B.Cu" signal "BOTTOM")
		(9 "F.Adhes" user "F.Adhesive")
		(11 "B.Adhes" user "B.Adhesive")
		(13 "F.Paste" user "Package Geometry/Pastemask Top")
		(15 "B.Paste" user "Package Geometry/Pastemask Bottom")
		(5 "F.SilkS" user "Ref Des/Silkscreen Top")
		(7 "B.SilkS" user "Ref Des/Silkscreen Bottom")
		(1 "F.Mask" user "Board Geometry/Soldermask Top")
		(3 "B.Mask" user "Board Geometry/Soldermask Bottom")
		(17 "Dwgs.User" user "User.Drawings")
		(19 "Cmts.User" user "User.Comments")
		(21 "Eco1.User" user "User.Eco1")
		(23 "Eco2.User" user "User.Eco2")
		(25 "Edge.Cuts" user "Board Geometry/Outline")
		(27 "Margin" user)
		(31 "F.CrtYd" user "Package Geometry/Place Bound Top")
		(29 "B.CrtYd" user "Package Geometry/Place Bound Bottom")
		(35 "F.Fab" user "Ref Des/Assembly Top")
		(33 "B.Fab" user "Ref Des/Assembly Bottom")
	)
	(footprint ""
		(layer "F.Cu")
		(at 219.99829 -251.163836 -90)
		(property "Reference" "C4301"
			(at 0 0 270)
			(layer "F.SilkS")
			(hide yes)
			(effects
				(font
					(size 1.27 1.27)
				)
			)
		)
		(property "Value" ""
			(at 0 0 270)
			(layer "F.Fab")
			(effects
				(font
					(size 1.27 1.27)
				)
			)
		)
		(duplicate_pad_numbers_are_jumpers no)
		(fp_line
			(start -1.524 0.762)
			(end -1.524 -0.762)
			(stroke
				(width 0.1524)
				(type default)
			)
			(layer "F.SilkS")
		)
		(fp_line
			(start 1.524 0.762)
			(end -1.524 0.762)
			(stroke
				(width 0.1524)
				(type default)
			)
			(layer "F.SilkS")
		)
		(fp_line
			(start -1.524 -0.762)
			(end 1.524 -0.762)
			(stroke
				(width 0.1524)
				(type default)
			)
			(layer "F.SilkS")
		)
		(fp_line
			(start 1.524 -0.762)
			(end 1.524 0.762)
			(stroke
				(width 0.1524)
				(type default)
			)
			(layer "F.SilkS")
		)
		(fp_line
			(start -1.1049 0.724916)
			(end 1.1049 0.724916)
			(stroke
				(width 0.1)
				(type default)
			)
			(layer "F.Fab")
		)
		(fp_line
			(start 1.1049 0.724916)
			(end 1.1049 -0.724916)
			(stroke
				(width 0.1)
				(type default)
			)
			(layer "F.Fab")
		)
		(fp_line
			(start -1.1049 -0.724916)
			(end -1.1049 0.724916)
			(stroke
				(width 0.1)
				(type default)
			)
			(layer "F.Fab")
		)
		(fp_line
			(start 1.1049 -0.724916)
			(end -1.1049 -0.724916)
			(stroke
				(width 0.1)
				(type default)
			)
			(layer "F.Fab")
		)
		(pad "1" smd rect
			(at -0.889 0 90)
			(size 1.016 1.27)
			(layers "F.Cu" "F.Mask" "F.Paste")
			(net "P1V25_SERDES_VDDPLL_PEX1_C11")
		)
		(pad "2" smd rect
			(at 0.889 0 90)
			(size 1.016 1.27)
			(layers "F.Cu" "F.Mask" "F.Paste")
			(net "GND")
		)
		(zone
			(layer "F.Cu")
			(hatch none 0.5)
			(connect_pads
				(clearance 0)
			)
			(min_thickness 0.25)
			(keepout
				(tracks not_allowed)
				(vias allowed)
				(pads allowed)
				(copperpour not_allowed)
				(footprints allowed)
			)
			(placement
				(enabled no)
				(sheetname "")
			)
			(fill
				(thermal_gap 0.5)
				(thermal_bridge_width 0.5)
				(island_removal_mode 0)
			)
			(polygon
				(pts
					(xy 220.723206 -251.494036) (xy 219.273374 -251.494036) (xy 219.273374 -250.833636) (xy 220.723206 -250.833636)
				)
			)
		)
	)
	(footprint ""
		(layer "F.Cu")
		(at 441.921138 -102.880414 90)
		(property "Reference" "C616"
			(at 0 0 90)
			(layer "F.SilkS")
			(hide yes)
			(effects
				(font
					(size 1.27 1.27)
				)
			)
		)
		(property "Value" ""
			(at 0 0 90)
			(layer "F.Fab")
			(effects
				(font
					(size 1.27 1.27)
				)
			)
		)
		(duplicate_pad_numbers_are_jumpers no)
		(fp_line
			(start 0.7874 -0.4064)
			(end 0.7874 0.4064)
			(stroke
				(width 0.1524)
				(type default)
			)
			(layer "F.SilkS")
		)
		(fp_line
			(start -0.7874 -0.4064)
			(end 0.7874 -0.4064)
			(stroke
				(width 0.1524)
				(type default)
			)
			(layer "F.SilkS")
		)
		(fp_line
			(start 0.7874 0.4064)
			(end -0.7874 0.4064)
			(stroke
				(width 0.1524)
				(type default)
			)
			(layer "F.SilkS")
		)
		(fp_line
			(start -0.7874 0.4064)
			(end -0.7874 -0.4064)
			(stroke
				(width 0.1524)
				(type default)
			)
			(layer "F.SilkS")
		)
		(fp_line
			(start -0.12065 -0.305054)
			(end -0.12065 -0.2794)
			(stroke
				(width 0.1)
				(type default)
			)
			(layer "F.Fab")
		)
		(fp_line
			(start -0.67945 -0.305054)
			(end -0.12065 -0.305054)
			(stroke
				(width 0.1)
				(type default)
			)
			(layer "F.Fab")
		)
		(fp_line
			(start 0.67945 -0.3048)
			(end 0.67945 0.3048)
			(stroke
				(width 0.1)
				(type default)
			)
			(layer "F.Fab")
		)
		(fp_line
			(start 0.12065 -0.3048)
			(end 0.67945 -0.3048)
			(stroke
				(width 0.1)
				(type default)
			)
			(layer "F.Fab")
		)
		(fp_line
			(start 0.12065 -0.2794)
			(end 0.12065 -0.3048)
			(stroke
				(width 0.1)
				(type default)
			)
			(layer "F.Fab")
		)
		(fp_line
			(start -0.12065 -0.2794)
			(end 0.12065 -0.2794)
			(stroke
				(width 0.1)
				(type default)
			)
			(layer "F.Fab")
		)
		(fp_line
			(start 0.120396 0.2794)
			(end -0.12065 0.2794)
			(stroke
				(width 0.1)
				(type default)
			)
			(layer "F.Fab")
		)
		(fp_line
			(start -0.12065 0.2794)
			(end -0.12065 0.3048)
			(stroke
				(width 0.1)
				(type default)
			)
			(layer "F.Fab")
		)
		(fp_line
			(start 0.67945 0.3048)
			(end 0.120396 0.3048)
			(stroke
				(width 0.1)
				(type default)
			)
			(layer "F.Fab")
		)
		(fp_line
			(start 0.120396 0.3048)
			(end 0.120396 0.2794)
			(stroke
				(width 0.1)
				(type default)
			)
			(layer "F.Fab")
		)
		(fp_line
			(start -0.12065 0.3048)
			(end -0.67945 0.3048)
			(stroke
				(width 0.1)
				(type default)
			)
			(layer "F.Fab")
		)
		(fp_line
			(start -0.67945 0.3048)
			(end -0.67945 -0.305054)
			(stroke
				(width 0.1)
				(type default)
			)
			(layer "F.Fab")
		)
		(pad "1" smd circle
			(at -0.40005 0 90)
			(size 0 0)
			(layers "F.Cu" "F.Mask" "F.Paste")
			(net "P3V3_AUX")
		)
		(pad "2" smd circle
			(at 0.40005 0 90)
			(size 0 0)
			(layers "F.Cu" "F.Mask" "F.Paste")
			(net "GND")
		)
	)
	(footprint ""
		(layer "F.Cu")
		(at 14.354556 -135.993632 -90)
		(property "Reference" "PC308"
			(at 0 0 270)
			(layer "F.SilkS")
			(hide yes)
			(effects
				(font
					(size 1.27 1.27)
				)
			)
		)
		(property "Value" ""
			(at 0 0 270)
			(layer "F.Fab")
			(effects
				(font
					(size 1.27 1.27)
				)
			)
		)
		(duplicate_pad_numbers_are_jumpers no)
		(fp_line
			(start -0.7874 0.4064)
			(end -0.7874 -0.4064)
			(stroke
				(width 0.1524)
				(type default)
			)
			(layer "F.SilkS")
		)
		(fp_line
			(start 0.7874 0.4064)
			(end -0.7874 0.4064)
			(stroke
				(width 0.1524)
				(type default)
			)
			(layer "F.SilkS")
		)
		(fp_line
			(start -0.7874 -0.4064)
			(end 0.7874 -0.4064)
			(stroke
				(width 0.1524)
				(type default)
			)
			(layer "F.SilkS")
		)
		(fp_line
			(start 0.7874 -0.4064)
			(end 0.7874 0.4064)
			(stroke
				(width 0.1524)
				(type default)
			)
			(layer "F.SilkS")
		)
		(fp_line
			(start -0.67945 0.3048)
			(end -0.67945 -0.305054)
			(stroke
				(width 0.1)
				(type default)
			)
			(layer "F.Fab")
		)
		(fp_line
			(start -0.12065 0.3048)
			(end -0.67945 0.3048)
			(stroke
				(width 0.1)
				(type default)
			)
			(layer "F.Fab")
		)
		(fp_line
			(start 0.120396 0.3048)
			(end 0.120396 0.2794)
			(stroke
				(width 0.1)
				(type default)
			)
			(layer "F.Fab")
		)
		(fp_line
			(start 0.67945 0.3048)
			(end 0.120396 0.3048)
			(stroke
				(width 0.1)
				(type default)
			)
			(layer "F.Fab")
		)
		(fp_line
			(start -0.12065 0.2794)
			(end -0.12065 0.3048)
			(stroke
				(width 0.1)
				(type default)
			)
			(layer "F.Fab")
		)
		(fp_line
			(start 0.120396 0.2794)
			(end -0.12065 0.2794)
			(stroke
				(width 0.1)
				(type default)
			)
			(layer "F.Fab")
		)
		(fp_line
			(start -0.12065 -0.2794)
			(end 0.12065 -0.2794)
			(stroke
				(width 0.1)
				(type default)
			)
			(layer "F.Fab")
		)
		(fp_line
			(start 0.12065 -0.2794)
			(end 0.12065 -0.3048)
			(stroke
				(width 0.1)
				(type default)
			)
			(layer "F.Fab")
		)
		(fp_line
			(start 0.12065 -0.3048)
			(end 0.67945 -0.3048)
			(stroke
				(width 0.1)
				(type default)
			)
			(layer "F.Fab")
		)
		(fp_line
			(start 0.67945 -0.3048)
			(end 0.67945 0.3048)
			(stroke
				(width 0.1)
				(type default)
			)
			(layer "F.Fab")
		)
		(fp_line
			(start -0.67945 -0.305054)
			(end -0.12065 -0.305054)
			(stroke
				(width 0.1)
				(type default)
			)
			(layer "F.Fab")
		)
		(fp_line
			(start -0.12065 -0.305054)
			(end -0.12065 -0.2794)
			(stroke
				(width 0.1)
				(type default)
			)
			(layer "F.Fab")
		)
		(pad "1" smd circle
			(at -0.40005 0 270)
			(size 0 0)
			(layers "F.Cu" "F.Mask" "F.Paste")
			(net "P12V_NIC0_R")
		)
		(pad "2" smd circle
			(at 0.40005 0 270)
			(size 0 0)
			(layers "F.Cu" "F.Mask" "F.Paste")
			(net "GND")
		)
	)
	(footprint ""
		(layer "F.Cu")
		(at 37.054028 -147.969224 90)
		(property "Reference" "C845"
			(at 0 0 90)
			(layer "F.SilkS")
			(hide yes)
			(effects
				(font
					(size 1.27 1.27)
				)
			)
		)
		(property "Value" ""
			(at 0 0 90)
			(layer "F.Fab")
			(effects
				(font
					(size 1.27 1.27)
				)
			)
		)
		(duplicate_pad_numbers_are_jumpers no)
		(fp_line
			(start 1.524 -0.762)
			(end 1.524 0.762)
			(stroke
				(width 0.1524)
				(type default)
			)
			(layer "F.SilkS")
		)
		(fp_line
			(start -1.524 -0.762)
			(end 1.524 -0.762)
			(stroke
				(width 0.1524)
				(type default)
			)
			(layer "F.SilkS")
		)
		(fp_line
			(start 1.524 0.762)
			(end -1.524 0.762)
			(stroke
				(width 0.1524)
				(type default)
			)
			(layer "F.SilkS")
		)
		(fp_line
			(start -1.524 0.762)
			(end -1.524 -0.762)
			(stroke
				(width 0.1524)
				(type default)
			)
			(layer "F.SilkS")
		)
		(fp_line
			(start 1.1049 -0.724916)
			(end -1.1049 -0.724916)
			(stroke
				(width 0.1)
				(type default)
			)
			(layer "F.Fab")
		)
		(fp_line
			(start -1.1049 -0.724916)
			(end -1.1049 0.724916)
			(stroke
				(width 0.1)
				(type default)
			)
			(layer "F.Fab")
		)
		(fp_line
			(start 1.1049 0.724916)
			(end 1.1049 -0.724916)
			(stroke
				(width 0.1)
				(type default)
			)
			(layer "F.Fab")
		)
		(fp_line
			(start -1.1049 0.724916)
			(end 1.1049 0.724916)
			(stroke
				(width 0.1)
				(type default)
			)
			(layer "F.Fab")
		)
		(pad "1" smd rect
			(at -0.889 0 270)
			(size 1.016 1.27)
			(layers "F.Cu" "F.Mask" "F.Paste")
			(net "P12V_NIC0")
		)
		(pad "2" smd rect
			(at 0.889 0 270)
			(size 1.016 1.27)
			(layers "F.Cu" "F.Mask" "F.Paste")
			(net "GND")
		)
	)
	(footprint ""
		(layer "F.Cu")
		(at 331.778102 -90.666316)
		(property "Reference" "R1162"
			(at 0 0 0)
			(layer "F.SilkS")
			(hide yes)
			(effects
				(font
					(size 1.27 1.27)
				)
			)
		)
		(property "Value" ""
			(at 0 0 0)
			(layer "F.Fab")
			(effects
				(font
					(size 1.27 1.27)
				)
			)
		)
		(duplicate_pad_numbers_are_jumpers no)
		(fp_line
			(start -1.2954 -0.5842)
			(end 1.2954 -0.5842)
			(stroke
				(width 0.1524)
				(type default)
			)
			(layer "F.SilkS")
		)
		(fp_line
			(start -1.2954 0.5842)
			(end -1.2954 -0.5842)
			(stroke
				(width 0.1524)
				(type default)
			)
			(layer "F.SilkS")
		)
		(fp_line
			(start 1.2954 -0.5842)
			(end 1.2954 0.5842)
			(stroke
				(width 0.1524)
				(type default)
			)
			(layer "F.SilkS")
		)
		(fp_line
			(start 1.2954 0.5842)
			(end -1.2954 0.5842)
			(stroke
				(width 0.1524)
				(type default)
			)
			(layer "F.SilkS")
		)
		(fp_line
			(start -1.1938 -0.406654)
			(end -0.8636 -0.406654)
			(stroke
				(width 0.1)
				(type default)
			)
			(layer "F.Fab")
		)
		(fp_line
			(start -1.1938 0.4064)
			(end -1.1938 -0.406654)
			(stroke
				(width 0.1)
				(type default)
			)
			(layer "F.Fab")
		)
		(fp_line
			(start -0.8636 -0.4572)
			(end 0.8636 -0.4572)
			(stroke
				(width 0.1)
				(type default)
			)
			(layer "F.Fab")
		)
		(fp_line
			(start -0.8636 -0.406654)
			(end -0.8636 -0.4572)
			(stroke
				(width 0.1)
				(type default)
			)
			(layer "F.Fab")
		)
		(fp_line
			(start -0.8636 0.4064)
			(end -1.1938 0.4064)
			(stroke
				(width 0.1)
				(type default)
			)
			(layer "F.Fab")
		)
		(fp_line
			(start -0.8636 0.4318)
			(end -0.8636 0.4064)
			(stroke
				(width 0.1)
				(type default)
			)
			(layer "F.Fab")
		)
		(fp_line
			(start -0.8636 0.4572)
			(end -0.8636 0.4318)
			(stroke
				(width 0.1)
				(type default)
			)
			(layer "F.Fab")
		)
		(fp_line
			(start 0.8636 -0.4572)
			(end 0.8636 -0.406654)
			(stroke
				(width 0.1)
				(type default)
			)
			(layer "F.Fab")
		)
		(fp_line
			(start 0.8636 -0.406654)
			(end 1.1938 -0.406654)
			(stroke
				(width 0.1)
				(type default)
			)
			(layer "F.Fab")
		)
		(fp_line
			(start 0.8636 0.4064)
			(end 0.8636 0.4572)
			(stroke
				(width 0.1)
				(type default)
			)
			(layer "F.Fab")
		)
		(fp_line
			(start 0.8636 0.4572)
			(end -0.8636 0.4572)
			(stroke
				(width 0.1)
				(type default)
			)
			(layer "F.Fab")
		)
		(fp_line
			(start 1.1938 -0.406654)
			(end 1.1938 0.4064)
			(stroke
				(width 0.1)
				(type default)
			)
			(layer "F.Fab")
		)
		(fp_line
			(start 1.1938 0.4064)
			(end 0.8636 0.4064)
			(stroke
				(width 0.1)
				(type default)
			)
			(layer "F.Fab")
		)
		(pad "1" smd rect
			(at -0.7366 0 270)
			(size 0.7112 0.8128)
			(layers "F.Cu" "F.Mask" "F.Paste")
			(net "P3V3_VDD_9ZXL0851_8_15")
		)
		(pad "2" smd rect
			(at 0.7366 0 270)
			(size 0.7112 0.8128)
			(layers "F.Cu" "F.Mask" "F.Paste")
			(net "P3V3_VDDAR_9ZXL0851_8_15")
		)
	)
	(footprint ""
		(layer "F.Cu")
		(at 14.670786 -112.139476 -90)
		(property "Reference" "PR6916"
			(at 0 0 270)
			(layer "F.SilkS")
			(hide yes)
			(effects
				(font
					(size 1.27 1.27)
				)
			)
		)
		(property "Value" ""
			(at 0 0 270)
			(layer "F.Fab")
			(effects
				(font
					(size 1.27 1.27)
				)
			)
		)
		(duplicate_pad_numbers_are_jumpers no)
		(fp_line
			(start -0.7874 0.4064)
			(end -0.7874 -0.4064)
			(stroke
				(width 0.1524)
				(type default)
			)
			(layer "F.SilkS")
		)
		(fp_line
			(start 0.7874 0.4064)
			(end -0.7874 0.4064)
			(stroke
				(width 0.1524)
				(type default)
			)
			(layer "F.SilkS")
		)
		(fp_line
			(start -0.7874 -0.4064)
			(end 0.7874 -0.4064)
			(stroke
				(width 0.1524)
				(type default)
			)
			(layer "F.SilkS")
		)
		(fp_line
			(start 0.7874 -0.4064)
			(end 0.7874 0.4064)
			(stroke
				(width 0.1524)
				(type default)
			)
			(layer "F.SilkS")
		)
		(fp_line
			(start -0.67945 0.3048)
			(end -0.67945 -0.305054)
			(stroke
				(width 0.1)
				(type default)
			)
			(layer "F.Fab")
		)
		(fp_line
			(start -0.12065 0.3048)
			(end -0.67945 0.3048)
			(stroke
				(width 0.1)
				(type default)
			)
			(layer "F.Fab")
		)
		(fp_line
			(start 0.120396 0.3048)
			(end 0.120396 0.2794)
			(stroke
				(width 0.1)
				(type default)
			)
			(layer "F.Fab")
		)
		(fp_line
			(start 0.67945 0.3048)
			(end 0.120396 0.3048)
			(stroke
				(width 0.1)
				(type default)
			)
			(layer "F.Fab")
		)
		(fp_line
			(start -0.12065 0.2794)
			(end -0.12065 0.3048)
			(stroke
				(width 0.1)
				(type default)
			)
			(layer "F.Fab")
		)
		(fp_line
			(start 0.120396 0.2794)
			(end -0.12065 0.2794)
			(stroke
				(width 0.1)
				(type default)
			)
			(layer "F.Fab")
		)
		(fp_line
			(start -0.12065 -0.2794)
			(end 0.12065 -0.2794)
			(stroke
				(width 0.1)
				(type default)
			)
			(layer "F.Fab")
		)
		(fp_line
			(start 0.12065 -0.2794)
			(end 0.12065 -0.3048)
			(stroke
				(width 0.1)
				(type default)
			)
			(layer "F.Fab")
		)
		(fp_line
			(start 0.12065 -0.3048)
			(end 0.67945 -0.3048)
			(stroke
				(width 0.1)
				(type default)
			)
			(layer "F.Fab")
		)
		(fp_line
			(start 0.67945 -0.3048)
			(end 0.67945 0.3048)
			(stroke
				(width 0.1)
				(type default)
			)
			(layer "F.Fab")
		)
		(fp_line
			(start -0.67945 -0.305054)
			(end -0.12065 -0.305054)
			(stroke
				(width 0.1)
				(type default)
			)
			(layer "F.Fab")
		)
		(fp_line
			(start -0.12065 -0.305054)
			(end -0.12065 -0.2794)
			(stroke
				(width 0.1)
				(type default)
			)
			(layer "F.Fab")
		)
		(pad "1" smd circle
			(at -0.40005 0 270)
			(size 0 0)
			(layers "F.Cu" "F.Mask" "F.Paste")
			(net "P3V3_NIC0_CO_ILIMIT")
		)
		(pad "2" smd circle
			(at 0.40005 0 270)
			(size 0 0)
			(layers "F.Cu" "F.Mask" "F.Paste")
			(net "GND")
		)
	)
	(footprint ""
		(layer "F.Cu")
		(at 2.718054 -255.046734 -90)
		(property "Reference" "R6470"
			(at 0 0 270)
			(layer "F.SilkS")
			(hide yes)
			(effects
				(font
					(size 1.27 1.27)
				)
			)
		)
		(property "Value" ""
			(at 0 0 270)
			(layer "F.Fab")
			(effects
				(font
					(size 1.27 1.27)
				)
			)
		)
		(duplicate_pad_numbers_are_jumpers no)
		(fp_line
			(start -0.7874 0.4064)
			(end -0.7874 -0.4064)
			(stroke
				(width 0.1524)
				(type default)
			)
			(layer "F.SilkS")
		)
		(fp_line
			(start 0.7874 0.4064)
			(end -0.7874 0.4064)
			(stroke
				(width 0.1524)
				(type default)
			)
			(layer "F.SilkS")
		)
		(fp_line
			(start -0.7874 -0.4064)
			(end 0.7874 -0.4064)
			(stroke
				(width 0.1524)
				(type default)
			)
			(layer "F.SilkS")
		)
		(fp_line
			(start 0.7874 -0.4064)
			(end 0.7874 0.4064)
			(stroke
				(width 0.1524)
				(type default)
			)
			(layer "F.SilkS")
		)
		(fp_line
			(start -0.67945 0.3048)
			(end -0.67945 -0.305054)
			(stroke
				(width 0.1)
				(type default)
			)
			(layer "F.Fab")
		)
		(fp_line
			(start -0.12065 0.3048)
			(end -0.67945 0.3048)
			(stroke
				(width 0.1)
				(type default)
			)
			(layer "F.Fab")
		)
		(fp_line
			(start 0.120396 0.3048)
			(end 0.120396 0.2794)
			(stroke
				(width 0.1)
				(type default)
			)
			(layer "F.Fab")
		)
		(fp_line
			(start 0.67945 0.3048)
			(end 0.120396 0.3048)
			(stroke
				(width 0.1)
				(type default)
			)
			(layer "F.Fab")
		)
		(fp_line
			(start -0.12065 0.2794)
			(end -0.12065 0.3048)
			(stroke
				(width 0.1)
				(type default)
			)
			(layer "F.Fab")
		)
		(fp_line
			(start 0.120396 0.2794)
			(end -0.12065 0.2794)
			(stroke
				(width 0.1)
				(type default)
			)
			(layer "F.Fab")
		)
		(fp_line
			(start -0.12065 -0.2794)
			(end 0.12065 -0.2794)
			(stroke
				(width 0.1)
				(type default)
			)
			(layer "F.Fab")
		)
		(fp_line
			(start 0.12065 -0.2794)
			(end 0.12065 -0.3048)
			(stroke
				(width 0.1)
				(type default)
			)
			(layer "F.Fab")
		)
		(fp_line
			(start 0.12065 -0.3048)
			(end 0.67945 -0.3048)
			(stroke
				(width 0.1)
				(type default)
			)
			(layer "F.Fab")
		)
		(fp_line
			(start 0.67945 -0.3048)
			(end 0.67945 0.3048)
			(stroke
				(width 0.1)
				(type default)
			)
			(layer "F.Fab")
		)
		(fp_line
			(start -0.67945 -0.305054)
			(end -0.12065 -0.305054)
			(stroke
				(width 0.1)
				(type default)
			)
			(layer "F.Fab")
		)
		(fp_line
			(start -0.12065 -0.305054)
			(end -0.12065 -0.2794)
			(stroke
				(width 0.1)
				(type default)
			)
			(layer "F.Fab")
		)
		(pad "1" smd circle
			(at -0.40005 0 270)
			(size 0 0)
			(layers "F.Cu" "F.Mask" "F.Paste")
			(net "P1V25_SERDES_VDDPLL_PEX0")
		)
		(pad "2" smd circle
			(at 0.40005 0 270)
			(size 0 0)
			(layers "F.Cu" "F.Mask" "F.Paste")
			(net "P1V25_SERDES_VDDPLL_PEX0_C7")
		)
	)
)
